(kicad_pcb
	(version 20260206)
	(generator "pcbnew")
	(generator_version "10.0")
	(general
		(thickness 1.6)
		(legacy_teardrops no)
	)
	(paper "A4")
	(title_block
		(title "fcb — 12433-1M.1206WZS1330.brd")
		(comment 1 "Open Vault / Knox (Wiwynn) / footprints 42-45 of 495")
	)
	(layers
		(0 "F.Cu" signal "TOP")
		(4 "In1.Cu" signal "L2GND")
		(6 "In2.Cu" signal "L3VCC")
		(2 "B.Cu" signal "BOTTOM")
		(9 "F.Adhes" user "F.Adhesive")
		(11 "B.Adhes" user "B.Adhesive")
		(13 "F.Paste" user "Package Geometry/Pastemask Top")
		(15 "B.Paste" user "Package Geometry/Pastemask Bottom")
		(5 "F.SilkS" user "Ref Des/Silkscreen Top")
		(7 "B.SilkS" user "Ref Des/Silkscreen Bottom")
		(1 "F.Mask" user "Board Geometry/Soldermask Top")
		(3 "B.Mask" user "Board Geometry/Soldermask Bottom")
		(17 "Dwgs.User" user "User.Drawings")
		(19 "Cmts.User" user "User.Comments")
		(21 "Eco1.User" user "User.Eco1")
		(23 "Eco2.User" user "User.Eco2")
		(25 "Edge.Cuts" user "Board Geometry/Outline")
		(27 "Margin" user)
		(31 "F.CrtYd" user "Package Geometry/Place Bound Top")
		(29 "B.CrtYd" user "Package Geometry/Place Bound Bottom")
		(35 "F.Fab" user "Ref Des/Assembly Top")
		(33 "B.Fab" user "Ref Des/Assembly Bottom")
	)
	(footprint ""
		(layer "F.Cu")
		(at 30.36189 -159.849566 180)
		(property "Reference" "U1"
			(at 0 0 180)
			(layer "F.SilkS")
			(hide yes)
			(effects
				(font
					(size 1.27 1.27)
				)
			)
		)
		(property "Value" "NCT7904D-GP"
			(at -4.064 -8.5852 180)
			(unlocked yes)
			(layer "F.Fab")
			(hide yes)
			(effects
				(font
					(size 1.016 1.016)
					(thickness 0.1524)
				)
			)
		)
		(property "Device Type" "LQFP48H63"
			(at -4.064 -10.3632 180)
			(unlocked yes)
			(layer "F.Fab")
			(hide yes)
			(effects
				(font
					(size 1.016 1.016)
					(thickness 0.1524)
				)
			)
		)
		(duplicate_pad_numbers_are_jumpers no)
		(fp_line
			(start 5.5118 5.5118)
			(end 5.5118 3.0226)
			(stroke
				(width 0.1524)
				(type default)
			)
			(layer "F.SilkS")
		)
		(fp_line
			(start 5.5118 -3.0734)
			(end 5.4864 -3.0734)
			(stroke
				(width 0.1524)
				(type default)
			)
			(layer "F.SilkS")
		)
		(fp_line
			(start 5.5118 -5.5118)
			(end 5.5118 -3.0734)
			(stroke
				(width 0.1524)
				(type default)
			)
			(layer "F.SilkS")
		)
		(fp_line
			(start 5.4864 -3.0734)
			(end 3.048 -5.5118)
			(stroke
				(width 0.1524)
				(type default)
			)
			(layer "F.SilkS")
		)
		(fp_line
			(start 5.1562 1.24968)
			(end 5.9182 1.24968)
			(stroke
				(width 0.1524)
				(type default)
			)
			(layer "F.SilkS")
		)
		(fp_line
			(start 5.1562 -1.24968)
			(end 5.6642 -1.24968)
			(stroke
				(width 0.1524)
				(type default)
			)
			(layer "F.SilkS")
		)
		(fp_line
			(start 3.048 -5.5118)
			(end 5.5118 -5.5118)
			(stroke
				(width 0.1524)
				(type default)
			)
			(layer "F.SilkS")
		)
		(fp_line
			(start 2.9718 5.5118)
			(end 5.5118 5.5118)
			(stroke
				(width 0.1524)
				(type default)
			)
			(layer "F.SilkS")
		)
		(fp_line
			(start 2.25044 5.1562)
			(end 2.25044 5.6642)
			(stroke
				(width 0.1524)
				(type default)
			)
			(layer "F.SilkS")
		)
		(fp_line
			(start 0.75057 -5.1562)
			(end 0.75057 -5.6642)
			(stroke
				(width 0.1524)
				(type default)
			)
			(layer "F.SilkS")
		)
		(fp_line
			(start -0.25019 5.1562)
			(end -0.25019 5.9182)
			(stroke
				(width 0.1524)
				(type default)
			)
			(layer "F.SilkS")
		)
		(fp_line
			(start -1.75006 -5.1562)
			(end -1.75006 -5.9182)
			(stroke
				(width 0.1524)
				(type default)
			)
			(layer "F.SilkS")
		)
		(fp_line
			(start -2.74955 5.1562)
			(end -2.74955 5.6642)
			(stroke
				(width 0.1524)
				(type default)
			)
			(layer "F.SilkS")
		)
		(fp_line
			(start -3.0988 -5.5118)
			(end -5.5118 -5.5118)
			(stroke
				(width 0.1524)
				(type default)
			)
			(layer "F.SilkS")
		)
		(fp_line
			(start -5.1562 0.75057)
			(end -5.9182 0.75057)
			(stroke
				(width 0.1524)
				(type default)
			)
			(layer "F.SilkS")
		)
		(fp_line
			(start -5.1562 -1.75006)
			(end -5.6642 -1.75006)
			(stroke
				(width 0.1524)
				(type default)
			)
			(layer "F.SilkS")
		)
		(fp_line
			(start -5.5118 5.5118)
			(end -2.9972 5.5118)
			(stroke
				(width 0.1524)
				(type default)
			)
			(layer "F.SilkS")
		)
		(fp_line
			(start -5.5118 2.9718)
			(end -5.5118 5.5118)
			(stroke
				(width 0.1524)
				(type default)
			)
			(layer "F.SilkS")
		)
		(fp_line
			(start -5.5118 -5.5118)
			(end -5.5118 -2.9464)
			(stroke
				(width 0.1524)
				(type default)
			)
			(layer "F.SilkS")
		)
		(fp_poly
			(pts
				(xy 5.5118 -3.048) (xy 3.048 -5.5118) (xy 5.5118 -5.5118)
			)
			(stroke
				(width 0)
				(type default)
			)
			(fill no)
			(layer "F.SilkS")
		)
		(fp_poly
			(pts
				(xy 3.0734 -5.5118) (xy 5.5118 -5.5118) (xy 5.5118 -3.1496) (xy 5.4356 -3.1496)
			)
			(stroke
				(width 0)
				(type default)
			)
			(fill yes)
			(layer "F.SilkS")
		)
		(fp_rect
			(start -5.5118 5.5118)
			(end 5.5118 -5.5118)
			(stroke
				(width 0)
				(type default)
			)
			(fill no)
			(layer "F.CrtYd")
		)
		(fp_rect
			(start -5.5118 5.5118)
			(end 5.5118 -5.5118)
			(stroke
				(width 0)
				(type default)
			)
			(fill no)
			(layer "F.Fab")
		)
		(pad "1" smd rect
			(at 2.74955 -4.2418 180)
			(size 0.3048 1.524)
			(layers "F.Cu" "F.Mask" "F.Paste")
			(net "NCT7904_VREF")
		)
		(pad "2" smd rect
			(at 2.25044 -4.2418 180)
			(size 0.3048 1.524)
			(layers "F.Cu" "F.Mask" "F.Paste")
			(net "NCT7904_D1+")
		)
		(pad "3" smd rect
			(at 1.75006 -4.2418 180)
			(size 0.3048 1.524)
			(layers "F.Cu" "F.Mask" "F.Paste")
			(net "NCT7904_D1-")
		)
		(pad "4" smd rect
			(at 1.24968 -4.2418 180)
			(size 0.3048 1.524)
			(layers "F.Cu" "F.Mask" "F.Paste")
			(net "NCT7904_D2+")
		)
		(pad "5" smd rect
			(at 0.75057 -4.2418 180)
			(size 0.3048 1.524)
			(layers "F.Cu" "F.Mask" "F.Paste")
			(net "NCT7904_D2-")
		)
		(pad "6" smd rect
			(at 0.25019 -4.2418 180)
			(size 0.3048 1.524)
			(layers "F.Cu" "F.Mask" "F.Paste")
			(net "NCT7904_VSEN6")
		)
		(pad "7" smd rect
			(at -0.25019 -4.2418 180)
			(size 0.3048 1.524)
			(layers "F.Cu" "F.Mask" "F.Paste")
			(net "NCT7904_VSEN7")
		)
		(pad "8" smd rect
			(at -0.75057 -4.2418 180)
			(size 0.3048 1.524)
			(layers "F.Cu" "F.Mask" "F.Paste")
			(net "NCT7904_VSEN8")
		)
		(pad "9" smd rect
			(at -1.24968 -4.2418 180)
			(size 0.3048 1.524)
			(layers "F.Cu" "F.Mask" "F.Paste")
			(net "NCT7904_VSEN9")
		)
		(pad "10" smd rect
			(at -1.75006 -4.2418 180)
			(size 0.3048 1.524)
			(layers "F.Cu" "F.Mask" "F.Paste")
			(net "NCT7904_VSEN10")
		)
		(pad "11" smd rect
			(at -2.25044 -4.2418 180)
			(size 0.3048 1.524)
			(layers "F.Cu" "F.Mask" "F.Paste")
			(net "NCT7904_VSEN11")
		)
		(pad "12" smd rect
			(at -2.74955 -4.2418 180)
			(size 0.3048 1.524)
			(layers "F.Cu" "F.Mask" "F.Paste")
			(net "NCT7904_VSEN12")
		)
		(pad "13" smd rect
			(at -4.2418 -2.74955 180)
			(size 1.524 0.3048)
			(layers "F.Cu" "F.Mask" "F.Paste")
			(net "NCT7904_VSEN13")
		)
		(pad "14" smd rect
			(at -4.2418 -2.25044 180)
			(size 1.524 0.3048)
			(layers "F.Cu" "F.Mask" "F.Paste")
			(net "NCT7904_VSEN14")
		)
		(pad "15" smd rect
			(at -4.2418 -1.75006 180)
			(size 1.524 0.3048)
			(layers "F.Cu" "F.Mask" "F.Paste")
			(net "NCT7904_3VDD")
		)
		(pad "16" smd rect
			(at -4.2418 -1.24968 180)
			(size 1.524 0.3048)
			(layers "F.Cu" "F.Mask" "F.Paste")
			(net "NCT7904_3VSB")
		)
		(pad "17" smd rect
			(at -4.2418 -0.75057 180)
			(size 1.524 0.3048)
			(layers "F.Cu" "F.Mask" "F.Paste")
			(net "NCT7904_SMI")
		)
		(pad "18" smd rect
			(at -4.2418 -0.25019 180)
			(size 1.524 0.3048)
			(layers "F.Cu" "F.Mask" "F.Paste")
			(net "NCT7904_PROCHOT")
		)
		(pad "19" smd rect
			(at -4.2418 0.25019 180)
			(size 1.524 0.3048)
			(layers "F.Cu" "F.Mask" "F.Paste")
			(net "NCT7904_VSEN1")
		)
		(pad "20" smd rect
			(at -4.2418 0.75057 180)
			(size 1.524 0.3048)
			(layers "F.Cu" "F.Mask" "F.Paste")
			(net "NCT7904_PECI")
		)
		(pad "21" smd rect
			(at -4.2418 1.24968 180)
			(size 1.524 0.3048)
			(layers "F.Cu" "F.Mask" "F.Paste")
			(net "NCT7904_THERMTRIP")
		)
		(pad "22" smd rect
			(at -4.2418 1.75006 180)
			(size 1.524 0.3048)
			(layers "F.Cu" "F.Mask" "F.Paste")
			(net "NCT7904_CLKIN")
		)
		(pad "23" smd rect
			(at -4.2418 2.25044 180)
			(size 1.524 0.3048)
			(layers "F.Cu" "F.Mask" "F.Paste")
			(net "I2C_C_SCL_NCT7904")
		)
		(pad "24" smd rect
			(at -4.2418 2.74955 180)
			(size 1.524 0.3048)
			(layers "F.Cu" "F.Mask" "F.Paste")
			(net "I2C_C_SDA_NCT7904")
		)
		(pad "25" smd rect
			(at -2.74955 4.2418 180)
			(size 0.3048 1.524)
			(layers "F.Cu" "F.Mask" "F.Paste")
			(net "FANIN_1")
		)
		(pad "26" smd rect
			(at -2.25044 4.2418 180)
			(size 0.3048 1.524)
			(layers "F.Cu" "F.Mask" "F.Paste")
			(net "FANIN_2")
		)
		(pad "27" smd rect
			(at -1.75006 4.2418 180)
			(size 0.3048 1.524)
			(layers "F.Cu" "F.Mask" "F.Paste")
			(net "NCT7904_ADR")
		)
		(pad "28" smd rect
			(at -1.24968 4.2418 180)
			(size 0.3048 1.524)
			(layers "F.Cu" "F.Mask" "F.Paste")
			(net "NCT7904_RSTOUT")
		)
		(pad "29" smd rect
			(at -0.75057 4.2418 180)
			(size 0.3048 1.524)
			(layers "F.Cu" "F.Mask" "F.Paste")
			(net "FANIN_11")
		)
		(pad "30" smd rect
			(at -0.25019 4.2418 180)
			(size 0.3048 1.524)
			(layers "F.Cu" "F.Mask" "F.Paste")
			(net "NCT7904D_PWM1")
		)
		(pad "31" smd rect
			(at 0.25019 4.2418 180)
			(size 0.3048 1.524)
			(layers "F.Cu" "F.Mask" "F.Paste")
			(net "FANIN_12")
		)
		(pad "32" smd rect
			(at 0.75057 4.2418 180)
			(size 0.3048 1.524)
			(layers "F.Cu" "F.Mask" "F.Paste")
			(net "NCT7904D_PWM2")
		)
		(pad "33" smd rect
			(at 1.24968 4.2418 180)
			(size 0.3048 1.524)
			(layers "F.Cu" "F.Mask" "F.Paste")
			(net "FANIN_9")
		)
		(pad "34" smd rect
			(at 1.75006 4.2418 180)
			(size 0.3048 1.524)
			(layers "F.Cu" "F.Mask" "F.Paste")
			(net "NCT7904D_PWM3")
		)
		(pad "35" smd rect
			(at 2.25044 4.2418 180)
			(size 0.3048 1.524)
			(layers "F.Cu" "F.Mask" "F.Paste")
			(net "FANIN_10")
		)
		(pad "36" smd rect
			(at 2.74955 4.2418 180)
			(size 0.3048 1.524)
			(layers "F.Cu" "F.Mask" "F.Paste")
			(net "NCT7904D_PWM4")
		)
		(pad "37" smd rect
			(at 4.2418 2.74955 180)
			(size 1.524 0.3048)
			(layers "F.Cu" "F.Mask" "F.Paste")
			(net "FANIN_7")
		)
		(pad "38" smd rect
			(at 4.2418 2.25044 180)
			(size 1.524 0.3048)
			(layers "F.Cu" "F.Mask" "F.Paste")
			(net "FANIN_8")
		)
		(pad "39" smd rect
			(at 4.2418 1.75006 180)
			(size 1.524 0.3048)
			(layers "F.Cu" "F.Mask" "F.Paste")
			(net "FANIN_5")
		)
		(pad "40" smd rect
			(at 4.2418 1.24968 180)
			(size 1.524 0.3048)
			(layers "F.Cu" "F.Mask" "F.Paste")
			(net "FANIN_6")
		)
		(pad "41" smd rect
			(at 4.2418 0.75057 180)
			(size 1.524 0.3048)
			(layers "F.Cu" "F.Mask" "F.Paste")
			(net "FANIN_3")
		)
		(pad "42" smd rect
			(at 4.2418 0.25019 180)
			(size 1.524 0.3048)
			(layers "F.Cu" "F.Mask" "F.Paste")
			(net "FANIN_4")
		)
		(pad "43" smd rect
			(at 4.2418 -0.25019 180)
			(size 1.524 0.3048)
			(layers "F.Cu" "F.Mask" "F.Paste")
			(net "NCT7904_GND")
		)
		(pad "44" smd rect
			(at 4.2418 -0.75057 180)
			(size 1.524 0.3048)
			(layers "F.Cu" "F.Mask" "F.Paste")
			(net "NCT7904_TMPALM")
		)
		(pad "45" smd rect
			(at 4.2418 -1.24968 180)
			(size 1.524 0.3048)
			(layers "F.Cu" "F.Mask" "F.Paste")
			(net "NCT7904_LED")
		)
		(pad "46" smd rect
			(at 4.2418 -1.75006 180)
			(size 1.524 0.3048)
			(layers "F.Cu" "F.Mask" "F.Paste")
			(net "NCT7904_RESET")
		)
		(pad "47" smd rect
			(at 4.2418 -2.25044 180)
			(size 1.524 0.3048)
			(layers "F.Cu" "F.Mask" "F.Paste")
			(net "NCT7904_CASEOPEN")
		)
		(pad "48" smd rect
			(at 4.2418 -2.74955 180)
			(size 1.524 0.3048)
			(layers "F.Cu" "F.Mask" "F.Paste")
			(net "NCT7904_3VSB")
		)
	)
	(footprint ""
		(layer "F.Cu")
		(at 33.2232 -248.5644)
		(property "Reference" "C20"
			(at 0 0 0)
			(layer "F.SilkS")
			(hide yes)
			(effects
				(font
					(size 1.27 1.27)
				)
			)
		)
		(property "Value" "SCD1U50V3KX-GP"
			(at 0 -2.8194 0)
			(unlocked yes)
			(layer "F.Fab")
			(hide yes)
			(effects
				(font
					(size 1.016 1.016)
					(thickness 0.1524)
				)
			)
		)
		(property "Device Type" "C603H36"
			(at 0 -4.3434 0)
			(unlocked yes)
			(layer "F.Fab")
			(hide yes)
			(effects
				(font
					(size 1.016 1.016)
					(thickness 0.1524)
				)
			)
		)
		(duplicate_pad_numbers_are_jumpers no)
		(fp_line
			(start 0.508 0)
			(end -0.508 0)
			(stroke
				(width 0.2032)
				(type default)
			)
			(layer "F.SilkS")
		)
		(fp_rect
			(start -0.5842 1.3335)
			(end 0.5842 -1.3335)
			(stroke
				(width 0)
				(type default)
			)
			(fill no)
			(layer "F.CrtYd")
		)
		(fp_rect
			(start -0.5842 1.3335)
			(end 0.5842 -1.3335)
			(stroke
				(width 0)
				(type default)
			)
			(fill no)
			(layer "F.Fab")
		)
		(pad "1" smd custom
			(at 0 -0.762)
			(size 0.2159 0.2159)
			(layers "F.Cu" "F.Mask" "F.Paste")
			(net "P3V3")
			(options
				(clearance outline)
				(anchor circle)
			)
			(primitives
				(gr_poly
					(pts
						(arc
							(start -0.3302 -0.4318)
							(mid -0.402042 -0.402042)
							(end -0.4318 -0.3302)
						)
						(arc
							(start -0.4318 0.3302)
							(mid -0.402042 0.402042)
							(end -0.3302 0.4318)
						)
						(arc
							(start 0.3302 0.4318)
							(mid 0.402042 0.402042)
							(end 0.4318 0.3302)
						)
						(arc
							(start 0.4318 -0.3302)
							(mid 0.402042 -0.402042)
							(end 0.3302 -0.4318)
						)
					)
					(width 0)
					(fill yes)
				)
			)
		)
		(pad "2" smd custom
			(at 0 0.762)
			(size 0.2159 0.2159)
			(layers "F.Cu" "F.Mask" "F.Paste")
			(net "GND")
			(options
				(clearance outline)
				(anchor circle)
			)
			(primitives
				(gr_poly
					(pts
						(arc
							(start -0.3302 -0.4318)
							(mid -0.402042 -0.402042)
							(end -0.4318 -0.3302)
						)
						(arc
							(start -0.4318 0.3302)
							(mid -0.402042 0.402042)
							(end -0.3302 0.4318)
						)
						(arc
							(start 0.3302 0.4318)
							(mid 0.402042 0.402042)
							(end 0.4318 0.3302)
						)
						(arc
							(start 0.4318 -0.3302)
							(mid 0.402042 -0.402042)
							(end 0.3302 -0.4318)
						)
					)
					(width 0)
					(fill yes)
				)
			)
		)
	)
	(footprint ""
		(layer "F.Cu")
		(at 12.2682 -445.516 180)
		(property "Reference" "R97"
			(at 0 0 180)
			(layer "F.SilkS")
			(hide yes)
			(effects
				(font
					(size 1.27 1.27)
				)
			)
		)
		(property "Value" "4K7R2F-GP"
			(at 0.064008 -3.993896 180)
			(unlocked yes)
			(layer "F.Fab")
			(hide yes)
			(effects
				(font
					(size 1.016 1.016)
					(thickness 0.1524)
				)
			)
		)
		(property "Device Type" "R402H16"
			(at 0.064008 -5.517896 180)
			(unlocked yes)
			(layer "F.Fab")
			(hide yes)
			(effects
				(font
					(size 1.016 1.016)
					(thickness 0.1524)
				)
			)
		)
		(duplicate_pad_numbers_are_jumpers no)
		(fp_line
			(start 0.508 -0.9398)
			(end -0.508 -0.9398)
			(stroke
				(width 0.1524)
				(type default)
			)
			(layer "F.SilkS")
		)
		(fp_line
			(start -0.508 -0.9398)
			(end -0.508 0.9398)
			(stroke
				(width 0.1524)
				(type default)
			)
			(layer "F.SilkS")
		)
		(fp_rect
			(start -0.508 0.9398)
			(end 0.508 -0.9398)
			(stroke
				(width 0)
				(type default)
			)
			(fill no)
			(layer "F.CrtYd")
		)
		(fp_rect
			(start -0.508 0.9398)
			(end 0.508 -0.9398)
			(stroke
				(width 0)
				(type default)
			)
			(fill no)
			(layer "F.Fab")
		)
		(pad "1" smd custom
			(at 0 -0.4445 180)
			(size 0.1397 0.1397)
			(layers "F.Cu" "F.Mask" "F.Paste")
			(net "P12V")
			(options
				(clearance outline)
				(anchor circle)
			)
			(primitives
				(gr_poly
					(pts
						(arc
							(start -0.1778 -0.2794)
							(mid -0.249642 -0.249642)
							(end -0.2794 -0.1778)
						)
						(arc
							(start -0.2794 0.1778)
							(mid -0.249642 0.249642)
							(end -0.1778 0.2794)
						)
						(arc
							(start 0.1778 0.2794)
							(mid 0.249642 0.249642)
							(end 0.2794 0.1778)
						)
						(arc
							(start 0.2794 -0.1778)
							(mid 0.249642 -0.249642)
							(end 0.1778 -0.2794)
						)
					)
					(width 0)
					(fill yes)
				)
			)
		)
		(pad "2" smd custom
			(at 0 0.4445 180)
			(size 0.1397 0.1397)
			(layers "F.Cu" "F.Mask" "F.Paste")
			(net "FAN_TACH2")
			(options
				(clearance outline)
				(anchor circle)
			)
			(primitives
				(gr_poly
					(pts
						(arc
							(start -0.1778 -0.2794)
							(mid -0.249642 -0.249642)
							(end -0.2794 -0.1778)
						)
						(arc
							(start -0.2794 0.1778)
							(mid -0.249642 0.249642)
							(end -0.1778 0.2794)
						)
						(arc
							(start 0.1778 0.2794)
							(mid 0.249642 0.249642)
							(end 0.2794 0.1778)
						)
						(arc
							(start 0.2794 -0.1778)
							(mid 0.249642 -0.249642)
							(end 0.1778 -0.2794)
						)
					)
					(width 0)
					(fill yes)
				)
			)
		)
	)
	(footprint ""
		(layer "F.Cu")
		(at 23.876 -243.84 180)
		(property "Reference" "PR54"
			(at 0 0 180)
			(layer "F.SilkS")
			(hide yes)
			(effects
				(font
					(size 1.27 1.27)
				)
			)
		)
		(property "Value" "0R3J-0-U-GP"
			(at -0.0254 -2.5146 180)
			(unlocked yes)
			(layer "F.Fab")
			(hide yes)
			(effects
				(font
					(size 1.016 1.016)
					(thickness 0.1524)
				)
			)
		)
		(property "Device Type" "R603H22"
			(at -0.0254 -4.0386 180)
			(unlocked yes)
			(layer "F.Fab")
			(hide yes)
			(effects
				(font
					(size 1.016 1.016)
					(thickness 0.1524)
				)
			)
		)
		(duplicate_pad_numbers_are_jumpers no)
		(fp_line
			(start 0.2032 0)
			(end 0.4826 0)
			(stroke
				(width 0.2032)
				(type default)
			)
			(layer "F.SilkS")
		)
		(fp_line
			(start -0.4826 0)
			(end -0.2032 0)
			(stroke
				(width 0.2032)
				(type default)
			)
			(layer "F.SilkS")
		)
		(fp_rect
			(start -0.5842 1.3335)
			(end 0.5842 -1.3335)
			(stroke
				(width 0)
				(type default)
			)
			(fill no)
			(layer "F.CrtYd")
		)
		(fp_rect
			(start -0.5842 1.3335)
			(end 0.5842 -1.3335)
			(stroke
				(width 0)
				(type default)
			)
			(fill no)
			(layer "F.Fab")
		)
		(pad "1" smd custom
			(at 0 -0.762 180)
			(size 0.2159 0.2159)
			(layers "F.Cu" "F.Mask" "F.Paste")
			(net "P3V3_LX_COPPER")
			(options
				(clearance outline)
				(anchor circle)
			)
			(primitives
				(gr_poly
					(pts
						(arc
							(start -0.3302 -0.4318)
							(mid -0.402042 -0.402042)
							(end -0.4318 -0.3302)
						)
						(arc
							(start -0.4318 0.3302)
							(mid -0.402042 0.402042)
							(end -0.3302 0.4318)
						)
						(arc
							(start 0.3302 0.4318)
							(mid 0.402042 0.402042)
							(end 0.4318 0.3302)
						)
						(arc
							(start 0.4318 -0.3302)
							(mid 0.402042 -0.402042)
							(end 0.3302 -0.4318)
						)
					)
					(width 0)
					(fill yes)
				)
			)
		)
		(pad "2" smd custom
			(at 0 0.762 180)
			(size 0.2159 0.2159)
			(layers "F.Cu" "F.Mask" "F.Paste")
			(net "P3V3_LX_REV")
			(options
				(clearance outline)
				(anchor circle)
			)
			(primitives
				(gr_poly
					(pts
						(arc
							(start -0.3302 -0.4318)
							(mid -0.402042 -0.402042)
							(end -0.4318 -0.3302)
						)
						(arc
							(start -0.4318 0.3302)
							(mid -0.402042 0.402042)
							(end -0.3302 0.4318)
						)
						(arc
							(start 0.3302 0.4318)
							(mid 0.402042 0.402042)
							(end 0.4318 0.3302)
						)
						(arc
							(start 0.4318 -0.3302)
							(mid 0.402042 -0.402042)
							(end 0.3302 -0.4318)
						)
					)
					(width 0)
					(fill yes)
				)
			)
		)
	)
)
